# T6G (Grand Teton) — schematic netlist excerpt (pin names and nets, part order shuffled) for the footprints in the layout excerpt that follows; sources: Cadence DE-HDL packaged netlist, KiCad conversion of 04192023_DAF0TMB3IC0_F0TG_MB_C_brd_V02_OCP.brd

PC201_1  Q_CAP  0.1UF 25V 10% X7R  pkg 0402  page 208 : A = PVDD11_S3_P0_VCCS ; B = GND
R892  Q_RES  1K 1% CHIP  pkg 0201LF  page 342 : A = RT_CPU1_P2_ADDR1 ; B = GND
PC1321  Q_CAP  0.068UF 16V 10% X7R  pkg 0402  page 141 : A = P3V3_OCP_DVDT_2 ; B = GND

(kicad_pcb
	(version 20260206)
	(generator "pcbnew")
	(generator_version "10.0")
	(general
		(thickness 1.6)
		(legacy_teardrops no)
	)
	(paper "A4")
	(title_block
		(title "04192023_DAF0TMB3IC0_F0TG_MB_C_brd_V02_OCP.brd")
		(comment 1 "Grand Teton / footprints 3180-3182 of 8354")
	)
	(layers
		(0 "F.Cu" signal "TOP")
		(4 "In1.Cu" signal "GND")
		(6 "In2.Cu" signal "IN1")
		(8 "In3.Cu" signal "GND1")
		(10 "In4.Cu" signal "IN2")
		(12 "In5.Cu" signal "GND2")
		(14 "In6.Cu" signal "IN3")
		(16 "In7.Cu" signal "GND3")
		(18 "In8.Cu" signal "VCC")
		(20 "In9.Cu" signal "VCC1")
		(22 "In10.Cu" signal "GND4")
		(24 "In11.Cu" signal "IN4")
		(26 "In12.Cu" signal "GND5")
		(28 "In13.Cu" signal "IN5")
		(30 "In14.Cu" signal "GND6")
		(32 "In15.Cu" signal "IN6")
		(34 "In16.Cu" signal "GND7")
		(2 "B.Cu" signal "BOTTOM")
		(9 "F.Adhes" user "F.Adhesive")
		(11 "B.Adhes" user "B.Adhesive")
		(13 "F.Paste" user "Package Geometry/Pastemask Top")
		(15 "B.Paste" user "Package Geometry/Pastemask Bottom")
		(5 "F.SilkS" user "Ref Des/Silkscreen Top")
		(7 "B.SilkS" user "Ref Des/Silkscreen Bottom")
		(1 "F.Mask" user "Board Geometry/Soldermask Top")
		(3 "B.Mask" user "Board Geometry/Soldermask Bottom")
		(17 "Dwgs.User" user "User.Drawings")
		(19 "Cmts.User" user "User.Comments")
		(21 "Eco1.User" user "User.Eco1")
		(23 "Eco2.User" user "User.Eco2")
		(25 "Edge.Cuts" user "Board Geometry/Outline")
		(27 "Margin" user)
		(31 "F.CrtYd" user "Package Geometry/Place Bound Top")
		(29 "B.CrtYd" user "Package Geometry/Place Bound Bottom")
		(35 "F.Fab" user "Ref Des/Assembly Top")
		(33 "B.Fab" user "Ref Des/Assembly Bottom")
	)
	(footprint ""
		(layer "F.Cu")
		(at 97.177352 -74.76998)
		(property "Reference" "PC1321"
			(at 0 0 0)
			(layer "F.SilkS")
			(hide yes)
			(effects
				(font
					(size 1.27 1.27)
				)
			)
		)
		(property "Value" ""
			(at 0 0 0)
			(layer "F.Fab")
			(effects
				(font
					(size 1.27 1.27)
				)
			)
		)
		(duplicate_pad_numbers_are_jumpers no)
		(fp_line
			(start -0.7874 -0.4064)
			(end 0.7874 -0.4064)
			(stroke
				(width 0.1524)
				(type default)
			)
			(layer "F.SilkS")
		)
		(fp_line
			(start -0.7874 0.4064)
			(end -0.7874 -0.4064)
			(stroke
				(width 0.1524)
				(type default)
			)
			(layer "F.SilkS")
		)
		(fp_line
			(start 0.7874 -0.4064)
			(end 0.7874 0.4064)
			(stroke
				(width 0.1524)
				(type default)
			)
			(layer "F.SilkS")
		)
		(fp_line
			(start 0.7874 0.4064)
			(end -0.7874 0.4064)
			(stroke
				(width 0.1524)
				(type default)
			)
			(layer "F.SilkS")
		)
		(fp_line
			(start -0.67945 -0.305054)
			(end -0.12065 -0.305054)
			(stroke
				(width 0.1)
				(type default)
			)
			(layer "F.Fab")
		)
		(fp_line
			(start -0.67945 0.3048)
			(end -0.67945 -0.305054)
			(stroke
				(width 0.1)
				(type default)
			)
			(layer "F.Fab")
		)
		(fp_line
			(start -0.12065 -0.305054)
			(end -0.12065 -0.2794)
			(stroke
				(width 0.1)
				(type default)
			)
			(layer "F.Fab")
		)
		(fp_line
			(start -0.12065 -0.2794)
			(end 0.12065 -0.2794)
			(stroke
				(width 0.1)
				(type default)
			)
			(layer "F.Fab")
		)
		(fp_line
			(start -0.12065 0.2794)
			(end -0.12065 0.3048)
			(stroke
				(width 0.1)
				(type default)
			)
			(layer "F.Fab")
		)
		(fp_line
			(start -0.12065 0.3048)
			(end -0.67945 0.3048)
			(stroke
				(width 0.1)
				(type default)
			)
			(layer "F.Fab")
		)
		(fp_line
			(start 0.120396 0.2794)
			(end -0.12065 0.2794)
			(stroke
				(width 0.1)
				(type default)
			)
			(layer "F.Fab")
		)
		(fp_line
			(start 0.120396 0.3048)
			(end 0.120396 0.2794)
			(stroke
				(width 0.1)
				(type default)
			)
			(layer "F.Fab")
		)
		(fp_line
			(start 0.12065 -0.3048)
			(end 0.67945 -0.3048)
			(stroke
				(width 0.1)
				(type default)
			)
			(layer "F.Fab")
		)
		(fp_line
			(start 0.12065 -0.2794)
			(end 0.12065 -0.3048)
			(stroke
				(width 0.1)
				(type default)
			)
			(layer "F.Fab")
		)
		(fp_line
			(start 0.67945 -0.3048)
			(end 0.67945 0.3048)
			(stroke
				(width 0.1)
				(type default)
			)
			(layer "F.Fab")
		)
		(fp_line
			(start 0.67945 0.3048)
			(end 0.120396 0.3048)
			(stroke
				(width 0.1)
				(type default)
			)
			(layer "F.Fab")
		)
		(pad "1" smd circle
			(at -0.40005 0)
			(size 0 0)
			(layers "F.Cu" "F.Mask" "F.Paste")
			(net "P3V3_OCP_DVDT_2")
		)
		(pad "2" smd circle
			(at 0.40005 0)
			(size 0 0)
			(layers "F.Cu" "F.Mask" "F.Paste")
			(net "GND")
		)
	)
	(footprint ""
		(layer "F.Cu")
		(at 170.979846 -382.30429)
		(property "Reference" "R892"
			(at 0 0 0)
			(layer "F.SilkS")
			(hide yes)
			(effects
				(font
					(size 1.27 1.27)
				)
			)
		)
		(property "Value" ""
			(at 0 0 0)
			(layer "F.Fab")
			(effects
				(font
					(size 1.27 1.27)
				)
			)
		)
		(duplicate_pad_numbers_are_jumpers no)
		(fp_line
			(start -0.32512 -0.175006)
			(end 0.32512 -0.175006)
			(stroke
				(width 0.1)
				(type default)
			)
			(layer "F.Fab")
		)
		(fp_line
			(start -0.32512 0.175006)
			(end -0.32512 -0.175006)
			(stroke
				(width 0.1)
				(type default)
			)
			(layer "F.Fab")
		)
		(fp_line
			(start 0.32512 -0.175006)
			(end 0.32512 0.175006)
			(stroke
				(width 0.1)
				(type default)
			)
			(layer "F.Fab")
		)
		(fp_line
			(start 0.32512 0.175006)
			(end -0.32512 0.175006)
			(stroke
				(width 0.1)
				(type default)
			)
			(layer "F.Fab")
		)
		(pad "1" smd rect
			(at -0.2667 0)
			(size 0.3048 0.381)
			(layers "F.Cu" "F.Mask" "F.Paste")
			(net "RT_CPU1_P2_ADDR1")
		)
		(pad "2" smd rect
			(at 0.2667 0 180)
			(size 0.3048 0.381)
			(layers "F.Cu" "F.Mask" "F.Paste")
			(net "GND")
		)
	)
	(footprint ""
		(layer "F.Cu")
		(at 420.950136 -355.972364 90)
		(property "Reference" "PC201_1"
			(at 0 0 90)
			(layer "F.SilkS")
			(hide yes)
			(effects
				(font
					(size 1.27 1.27)
				)
			)
		)
		(property "Value" ""
			(at 0 0 90)
			(layer "F.Fab")
			(effects
				(font
					(size 1.27 1.27)
				)
			)
		)
		(duplicate_pad_numbers_are_jumpers no)
		(fp_line
			(start 0.7874 -0.4064)
			(end 0.7874 0.4064)
			(stroke
				(width 0.1524)
				(type default)
			)
			(layer "F.SilkS")
		)
		(fp_line
			(start -0.7874 -0.4064)
			(end 0.7874 -0.4064)
			(stroke
				(width 0.1524)
				(type default)
			)
			(layer "F.SilkS")
		)
		(fp_line
			(start 0.7874 0.4064)
			(end -0.7874 0.4064)
			(stroke
				(width 0.1524)
				(type default)
			)
			(layer "F.SilkS")
		)
		(fp_line
			(start -0.7874 0.4064)
			(end -0.7874 -0.4064)
			(stroke
				(width 0.1524)
				(type default)
			)
			(layer "F.SilkS")
		)
		(fp_line
			(start -0.12065 -0.305054)
			(end -0.12065 -0.2794)
			(stroke
				(width 0.1)
				(type default)
			)
			(layer "F.Fab")
		)
		(fp_line
			(start -0.67945 -0.305054)
			(end -0.12065 -0.305054)
			(stroke
				(width 0.1)
				(type default)
			)
			(layer "F.Fab")
		)
		(fp_line
			(start 0.67945 -0.3048)
			(end 0.67945 0.3048)
			(stroke
				(width 0.1)
				(type default)
			)
			(layer "F.Fab")
		)
		(fp_line
			(start 0.12065 -0.3048)
			(end 0.67945 -0.3048)
			(stroke
				(width 0.1)
				(type default)
			)
			(layer "F.Fab")
		)
		(fp_line
			(start 0.12065 -0.2794)
			(end 0.12065 -0.3048)
			(stroke
				(width 0.1)
				(type default)
			)
			(layer "F.Fab")
		)
		(fp_line
			(start -0.12065 -0.2794)
			(end 0.12065 -0.2794)
			(stroke
				(width 0.1)
				(type default)
			)
			(layer "F.Fab")
		)
		(fp_line
			(start 0.120396 0.2794)
			(end -0.12065 0.2794)
			(stroke
				(width 0.1)
				(type default)
			)
			(layer "F.Fab")
		)
		(fp_line
			(start -0.12065 0.2794)
			(end -0.12065 0.3048)
			(stroke
				(width 0.1)
				(type default)
			)
			(layer "F.Fab")
		)
		(fp_line
			(start 0.67945 0.3048)
			(end 0.120396 0.3048)
			(stroke
				(width 0.1)
				(type default)
			)
			(layer "F.Fab")
		)
		(fp_line
			(start 0.120396 0.3048)
			(end 0.120396 0.2794)
			(stroke
				(width 0.1)
				(type default)
			)
			(layer "F.Fab")
		)
		(fp_line
			(start -0.12065 0.3048)
			(end -0.67945 0.3048)
			(stroke
				(width 0.1)
				(type default)
			)
			(layer "F.Fab")
		)
		(fp_line
			(start -0.67945 0.3048)
			(end -0.67945 -0.305054)
			(stroke
				(width 0.1)
				(type default)
			)
			(layer "F.Fab")
		)
		(pad "1" smd circle
			(at -0.40005 0 90)
			(size 0 0)
			(layers "F.Cu" "F.Mask" "F.Paste")
			(net "PVDD11_S3_P0_VCCS")
		)
		(pad "2" smd circle
			(at 0.40005 0 90)
			(size 0 0)
			(layers "F.Cu" "F.Mask" "F.Paste")
			(net "GND")
		)
	)
)
